# BASEBOARD_FAB2 (Tioga Pass) — schematic netlist excerpt (pin names and nets, part order shuffled) for the footprints in the layout excerpt that follows; sources: Cadence DE-HDL packaged netlist, KiCad conversion of Wiwynn_Tioga_Pass_MB.brd

C1D1  CAP  220PF 50V 10% X7R  pkg 0402LF  page 206 : A = VSENSE_PVCCIN_CPU1_AVSP ; B = VSENSE_PVCCIN_CPU1_N
R4D49  RES  1.00K 1% CHIP  pkg 0402  page 213 : A = P3V3_STBY ; B = IRQ_PVCCIO_CPU1_VRHOT_N
CR1E1  DIODE  SDMK0340L EMPTY  pkg SM  page 161 : C = P5V_STBY ; A = FAN_PWM_OUT_SYS0_R

(kicad_pcb
	(version 20260206)
	(generator "pcbnew")
	(generator_version "10.0")
	(general
		(thickness 1.6)
		(legacy_teardrops no)
	)
	(paper "A4")
	(title_block
		(title "Wiwynn_Tioga_Pass_MB.brd")
		(comment 1 "Tioga Pass / footprints 1347-1349 of 4770")
	)
	(layers
		(0 "F.Cu" signal "TOP")
		(4 "In1.Cu" signal "L2GND")
		(6 "In2.Cu" signal "L3")
		(8 "In3.Cu" signal "L4GND")
		(10 "In4.Cu" signal "L5")
		(12 "In5.Cu" signal "L6GND")
		(14 "In6.Cu" signal "L7VCC")
		(16 "In7.Cu" signal "L8VCC")
		(18 "In8.Cu" signal "L9GND")
		(20 "In9.Cu" signal "L10")
		(22 "In10.Cu" signal "L11GND")
		(24 "In11.Cu" signal "L12")
		(26 "In12.Cu" signal "L13GND")
		(2 "B.Cu" signal "BOTTOM")
		(9 "F.Adhes" user "F.Adhesive")
		(11 "B.Adhes" user "B.Adhesive")
		(13 "F.Paste" user "Package Geometry/Pastemask Top")
		(15 "B.Paste" user "Package Geometry/Pastemask Bottom")
		(5 "F.SilkS" user "Ref Des/Silkscreen Top")
		(7 "B.SilkS" user "Ref Des/Silkscreen Bottom")
		(1 "F.Mask" user "Board Geometry/Soldermask Top")
		(3 "B.Mask" user "Board Geometry/Soldermask Bottom")
		(17 "Dwgs.User" user "User.Drawings")
		(19 "Cmts.User" user "User.Comments")
		(21 "Eco1.User" user "User.Eco1")
		(23 "Eco2.User" user "User.Eco2")
		(25 "Edge.Cuts" user "Board Geometry/Outline")
		(27 "Margin" user)
		(31 "F.CrtYd" user "Package Geometry/Place Bound Top")
		(29 "B.CrtYd" user "Package Geometry/Place Bound Bottom")
		(35 "F.Fab" user "Ref Des/Assembly Top")
		(33 "B.Fab" user "Ref Des/Assembly Bottom")
	)
	(footprint ""
		(layer "F.Cu")
		(at 164.084 -69.9262 90)
		(property "Reference" "R4D49"
			(at 0 0 90)
			(layer "F.SilkS")
			(hide yes)
			(effects
				(font
					(size 1.27 1.27)
				)
			)
		)
		(property "Value" ""
			(at 0 0 90)
			(layer "F.Fab")
			(effects
				(font
					(size 1.27 1.27)
				)
			)
		)
		(duplicate_pad_numbers_are_jumpers no)
		(fp_poly
			(pts
				(xy -0.2794 -0.1016) (xy 0.2794 -0.1016) (xy 0.2794 0.9906) (xy -0.2794 0.9906)
			)
			(stroke
				(width 0)
				(type default)
			)
			(fill no)
			(layer "F.CrtYd")
		)
		(fp_line
			(start 0.2794 -0.1016)
			(end -0.2794 -0.1016)
			(stroke
				(width 0.1)
				(type default)
			)
			(layer "F.Fab")
		)
		(fp_line
			(start -0.2794 -0.1016)
			(end -0.2794 0.9906)
			(stroke
				(width 0.1)
				(type default)
			)
			(layer "F.Fab")
		)
		(fp_line
			(start 0.2794 0.9906)
			(end 0.2794 -0.1016)
			(stroke
				(width 0.1)
				(type default)
			)
			(layer "F.Fab")
		)
		(fp_line
			(start -0.2794 0.9906)
			(end 0.2794 0.9906)
			(stroke
				(width 0.1)
				(type default)
			)
			(layer "F.Fab")
		)
		(pad "1" smd rect
			(at 0 0 90)
			(size 0.508 0.508)
			(layers "F.Cu" "F.Mask" "F.Paste")
			(net "P3V3_STBY")
		)
		(pad "2" smd rect
			(at 0 0.889 90)
			(size 0.508 0.508)
			(layers "F.Cu" "F.Mask" "F.Paste")
			(net "IRQ_PVCCIO_CPU1_VRHOT_N")
		)
		(zone
			(layer "F.Cu")
			(hatch none 0.5)
			(connect_pads
				(clearance 0)
			)
			(min_thickness 0.25)
			(keepout
				(tracks allowed)
				(vias not_allowed)
				(pads allowed)
				(copperpour not_allowed)
				(footprints allowed)
			)
			(placement
				(enabled no)
				(sheetname "")
			)
			(fill
				(thermal_gap 0.5)
				(thermal_bridge_width 0.5)
				(island_removal_mode 0)
			)
			(polygon
				(pts
					(xy 164.338 -69.6722) (xy 164.338 -70.1802) (xy 164.719 -70.1802) (xy 164.719 -69.6722)
				)
			)
		)
		(zone
			(layer "F.Cu")
			(hatch none 0.5)
			(connect_pads
				(clearance 0)
			)
			(min_thickness 0.25)
			(keepout
				(tracks not_allowed)
				(vias allowed)
				(pads allowed)
				(copperpour not_allowed)
				(footprints allowed)
			)
			(placement
				(enabled no)
				(sheetname "")
			)
			(fill
				(thermal_gap 0.5)
				(thermal_bridge_width 0.5)
				(island_removal_mode 0)
			)
			(polygon
				(pts
					(xy 164.719 -69.6722) (xy 164.719 -70.1802) (xy 164.338 -70.1802) (xy 164.338 -69.6722)
				)
			)
		)
	)
	(footprint ""
		(layer "F.Cu")
		(at 20.7518 -88.138 90)
		(property "Reference" "C1D1"
			(at 0 0 90)
			(layer "F.SilkS")
			(hide yes)
			(effects
				(font
					(size 1.27 1.27)
				)
			)
		)
		(property "Value" ""
			(at 0 0 90)
			(layer "F.Fab")
			(effects
				(font
					(size 1.27 1.27)
				)
			)
		)
		(duplicate_pad_numbers_are_jumpers no)
		(fp_rect
			(start -0.3048 -0.1016)
			(end 0.3048 0.9906)
			(stroke
				(width 0)
				(type default)
			)
			(fill no)
			(layer "F.CrtYd")
		)
		(fp_line
			(start 0.3048 -0.1016)
			(end -0.3048 -0.1016)
			(stroke
				(width 0.1)
				(type default)
			)
			(layer "F.Fab")
		)
		(fp_line
			(start -0.3048 -0.1016)
			(end -0.3048 0.9906)
			(stroke
				(width 0.1)
				(type default)
			)
			(layer "F.Fab")
		)
		(fp_line
			(start 0.3048 0.9906)
			(end 0.3048 -0.1016)
			(stroke
				(width 0.1)
				(type default)
			)
			(layer "F.Fab")
		)
		(fp_line
			(start -0.3048 0.9906)
			(end 0.3048 0.9906)
			(stroke
				(width 0.1)
				(type default)
			)
			(layer "F.Fab")
		)
		(pad "1" smd rect
			(at 0 0 90)
			(size 0.508 0.508)
			(layers "F.Cu" "F.Mask" "F.Paste")
			(net "VSENSE_PVCCIN_CPU1_AVSP")
		)
		(pad "2" smd rect
			(at 0 0.889 90)
			(size 0.508 0.508)
			(layers "F.Cu" "F.Mask" "F.Paste")
			(net "VSENSE_PVCCIN_CPU1_N")
		)
		(zone
			(layer "F.Cu")
			(hatch none 0.5)
			(connect_pads
				(clearance 0)
			)
			(min_thickness 0.25)
			(keepout
				(tracks allowed)
				(vias not_allowed)
				(pads allowed)
				(copperpour not_allowed)
				(footprints allowed)
			)
			(placement
				(enabled no)
				(sheetname "")
			)
			(fill
				(thermal_gap 0.5)
				(thermal_bridge_width 0.5)
				(island_removal_mode 0)
			)
			(polygon
				(pts
					(xy 21.0058 -87.884) (xy 21.3868 -87.884) (xy 21.3868 -88.392) (xy 21.0058 -88.392)
				)
			)
		)
		(zone
			(layer "F.Cu")
			(hatch none 0.5)
			(connect_pads
				(clearance 0)
			)
			(min_thickness 0.25)
			(keepout
				(tracks not_allowed)
				(vias allowed)
				(pads allowed)
				(copperpour not_allowed)
				(footprints allowed)
			)
			(placement
				(enabled no)
				(sheetname "")
			)
			(fill
				(thermal_gap 0.5)
				(thermal_bridge_width 0.5)
				(island_removal_mode 0)
			)
			(polygon
				(pts
					(xy 21.0058 -87.884) (xy 21.3868 -87.884) (xy 21.3868 -88.392) (xy 21.0058 -88.392)
				)
			)
		)
	)
	(footprint ""
		(layer "F.Cu")
		(at 24.7904 -42.6212 -90)
		(property "Reference" "CR1E1"
			(at 1.24587 0.2794 0)
			(unlocked yes)
			(layer "F.SilkS")
			(effects
				(font
					(size 0.7874 0.5842)
					(thickness 0.1524)
				)
				(justify left)
			)
		)
		(property "Value" ""
			(at 0 0 270)
			(layer "F.Fab")
			(effects
				(font
					(size 1.27 1.27)
				)
			)
		)
		(duplicate_pad_numbers_are_jumpers no)
		(fp_line
			(start -0.980186 2.623312)
			(end -0.980186 1.711706)
			(stroke
				(width 0.1524)
				(type default)
			)
			(layer "F.SilkS")
		)
		(fp_line
			(start -1.461008 1.711706)
			(end -0.980186 0.87884)
			(stroke
				(width 0.1524)
				(type default)
			)
			(layer "F.SilkS")
		)
		(fp_line
			(start -0.980186 1.711706)
			(end -1.461008 1.711706)
			(stroke
				(width 0.1524)
				(type default)
			)
			(layer "F.SilkS")
		)
		(fp_line
			(start -0.499364 1.711706)
			(end -0.980186 1.711706)
			(stroke
				(width 0.1524)
				(type default)
			)
			(layer "F.SilkS")
		)
		(fp_line
			(start -0.980186 0.87884)
			(end -0.499364 1.711706)
			(stroke
				(width 0.1524)
				(type default)
			)
			(layer "F.SilkS")
		)
		(fp_line
			(start -0.499364 0.87884)
			(end -1.461008 0.87884)
			(stroke
				(width 0.1524)
				(type default)
			)
			(layer "F.SilkS")
		)
		(fp_line
			(start -0.980186 -0.244602)
			(end -0.980186 0.87884)
			(stroke
				(width 0.1524)
				(type default)
			)
			(layer "F.SilkS")
		)
		(fp_rect
			(start 0.67437 2.04216)
			(end -0.67437 0.24384)
			(stroke
				(width 0)
				(type default)
			)
			(fill no)
			(layer "F.CrtYd")
		)
		(fp_line
			(start -0.67437 2.04216)
			(end 0.67437 2.04216)
			(stroke
				(width 0.1)
				(type default)
			)
			(layer "F.Fab")
		)
		(fp_line
			(start 0.67437 2.04216)
			(end 0.67437 0.24384)
			(stroke
				(width 0.1)
				(type default)
			)
			(layer "F.Fab")
		)
		(fp_line
			(start -1.461008 1.711706)
			(end -0.980186 0.87884)
			(stroke
				(width 0.1)
				(type default)
			)
			(layer "F.Fab")
		)
		(fp_line
			(start -0.980186 1.711706)
			(end -0.980186 2.623312)
			(stroke
				(width 0.1)
				(type default)
			)
			(layer "F.Fab")
		)
		(fp_line
			(start -0.499364 1.711706)
			(end -1.461008 1.711706)
			(stroke
				(width 0.1)
				(type default)
			)
			(layer "F.Fab")
		)
		(fp_line
			(start -0.980186 0.87884)
			(end -0.499364 1.711706)
			(stroke
				(width 0.1)
				(type default)
			)
			(layer "F.Fab")
		)
		(fp_line
			(start -0.980186 0.87884)
			(end -0.980186 -0.244602)
			(stroke
				(width 0.1)
				(type default)
			)
			(layer "F.Fab")
		)
		(fp_line
			(start -0.499364 0.87884)
			(end -1.461008 0.87884)
			(stroke
				(width 0.1)
				(type default)
			)
			(layer "F.Fab")
		)
		(fp_line
			(start -0.67437 0.24384)
			(end -0.67437 2.04216)
			(stroke
				(width 0.1)
				(type default)
			)
			(layer "F.Fab")
		)
		(fp_line
			(start 0.67437 0.24384)
			(end -0.67437 0.24384)
			(stroke
				(width 0.1)
				(type default)
			)
			(layer "F.Fab")
		)
		(pad "1" smd rect
			(at 0 0 270)
			(size 0.4064 1.016)
			(layers "F.Cu" "F.Mask" "F.Paste")
			(net "P5V_STBY")
		)
		(pad "2" smd rect
			(at 0 2.286 270)
			(size 0.4064 1.016)
			(layers "F.Cu" "F.Mask" "F.Paste")
			(net "FAN_PWM_OUT_SYS0_R")
		)
	)
)
